(kicad_pcb
	(version 20260206)
	(generator "pcbnew")
	(generator_version "10.0")
	(general
		(thickness 1.6)
		(legacy_teardrops no)
	)
	(paper "A4")
	(title_block
		(title "01162023_DA0F0TEBIF0_F0T_Expander_BD_F_brd_V02_OCP.brd")
		(comment 1 "Grand Teton / footprints 9585-9592 of 9728")
	)
	(layers
		(0 "F.Cu" signal "TOP")
		(4 "In1.Cu" signal "GND")
		(6 "In2.Cu" signal "VCC")
		(8 "In3.Cu" signal "VCC1")
		(10 "In4.Cu" signal "GND1")
		(12 "In5.Cu" signal "IN1")
		(14 "In6.Cu" signal "GND2")
		(16 "In7.Cu" signal "IN2")
		(18 "In8.Cu" signal "GND3")
		(20 "In9.Cu" signal "IN3")
		(22 "In10.Cu" signal "GND4")
		(24 "In11.Cu" signal "IN4")
		(26 "In12.Cu" signal "GND5")
		(28 "In13.Cu" signal "IN5")
		(30 "In14.Cu" signal "GND6")
		(32 "In15.Cu" signal "IN6")
		(34 "In16.Cu" signal "GND7")
		(2 "B.Cu" signal "BOTTOM")
		(9 "F.Adhes" user "F.Adhesive")
		(11 "B.Adhes" user "B.Adhesive")
		(13 "F.Paste" user "Package Geometry/Pastemask Top")
		(15 "B.Paste" user "Package Geometry/Pastemask Bottom")
		(5 "F.SilkS" user "Ref Des/Silkscreen Top")
		(7 "B.SilkS" user "Ref Des/Silkscreen Bottom")
		(1 "F.Mask" user "Board Geometry/Soldermask Top")
		(3 "B.Mask" user "Board Geometry/Soldermask Bottom")
		(17 "Dwgs.User" user "User.Drawings")
		(19 "Cmts.User" user "User.Comments")
		(21 "Eco1.User" user "User.Eco1")
		(23 "Eco2.User" user "User.Eco2")
		(25 "Edge.Cuts" user "Board Geometry/Outline")
		(27 "Margin" user)
		(31 "F.CrtYd" user "Package Geometry/Place Bound Top")
		(29 "B.CrtYd" user "Package Geometry/Place Bound Bottom")
		(35 "F.Fab" user "Ref Des/Assembly Top")
		(33 "B.Fab" user "Ref Des/Assembly Bottom")
	)
	(footprint ""
		(layer "B.Cu")
		(at 348.435168 -282.16733 90)
		(property "Reference" "R6767"
			(at 0 0 90)
			(layer "B.SilkS")
			(hide yes)
			(effects
				(font
					(size 1.27 1.27)
				)
				(justify mirror)
			)
		)
		(property "Value" ""
			(at 0 0 90)
			(layer "B.Fab")
			(effects
				(font
					(size 1.27 1.27)
				)
				(justify mirror)
			)
		)
		(duplicate_pad_numbers_are_jumpers no)
		(fp_line
			(start 0.7874 -0.4064)
			(end -0.7874 -0.4064)
			(stroke
				(width 0.1524)
				(type default)
			)
			(layer "B.SilkS")
		)
		(fp_line
			(start -0.7874 -0.4064)
			(end -0.7874 0.4064)
			(stroke
				(width 0.1524)
				(type default)
			)
			(layer "B.SilkS")
		)
		(fp_line
			(start 0.7874 0.4064)
			(end 0.7874 -0.4064)
			(stroke
				(width 0.1524)
				(type default)
			)
			(layer "B.SilkS")
		)
		(fp_line
			(start -0.7874 0.4064)
			(end 0.7874 0.4064)
			(stroke
				(width 0.1524)
				(type default)
			)
			(layer "B.SilkS")
		)
		(fp_line
			(start 0.67945 -0.305054)
			(end 0.12065 -0.305054)
			(stroke
				(width 0.1)
				(type default)
			)
			(layer "B.Fab")
		)
		(fp_line
			(start 0.12065 -0.305054)
			(end 0.12065 -0.2794)
			(stroke
				(width 0.1)
				(type default)
			)
			(layer "B.Fab")
		)
		(fp_line
			(start -0.12065 -0.3048)
			(end -0.67945 -0.3048)
			(stroke
				(width 0.1)
				(type default)
			)
			(layer "B.Fab")
		)
		(fp_line
			(start -0.67945 -0.3048)
			(end -0.67945 0.3048)
			(stroke
				(width 0.1)
				(type default)
			)
			(layer "B.Fab")
		)
		(fp_line
			(start 0.12065 -0.2794)
			(end -0.12065 -0.2794)
			(stroke
				(width 0.1)
				(type default)
			)
			(layer "B.Fab")
		)
		(fp_line
			(start -0.12065 -0.2794)
			(end -0.12065 -0.3048)
			(stroke
				(width 0.1)
				(type default)
			)
			(layer "B.Fab")
		)
		(fp_line
			(start 0.12065 0.2794)
			(end 0.12065 0.3048)
			(stroke
				(width 0.1)
				(type default)
			)
			(layer "B.Fab")
		)
		(fp_line
			(start -0.120396 0.2794)
			(end 0.12065 0.2794)
			(stroke
				(width 0.1)
				(type default)
			)
			(layer "B.Fab")
		)
		(fp_line
			(start 0.67945 0.3048)
			(end 0.67945 -0.305054)
			(stroke
				(width 0.1)
				(type default)
			)
			(layer "B.Fab")
		)
		(fp_line
			(start 0.12065 0.3048)
			(end 0.67945 0.3048)
			(stroke
				(width 0.1)
				(type default)
			)
			(layer "B.Fab")
		)
		(fp_line
			(start -0.120396 0.3048)
			(end -0.120396 0.2794)
			(stroke
				(width 0.1)
				(type default)
			)
			(layer "B.Fab")
		)
		(fp_line
			(start -0.67945 0.3048)
			(end -0.120396 0.3048)
			(stroke
				(width 0.1)
				(type default)
			)
			(layer "B.Fab")
		)
		(pad "1" smd circle
			(at 0.40005 0 270)
			(size 0 0)
			(layers "B.Cu" "B.Mask" "B.Paste")
			(net "P0V8_PEX2_VCC2")
		)
		(pad "2" smd circle
			(at -0.40005 0 270)
			(size 0 0)
			(layers "B.Cu" "B.Mask" "B.Paste")
			(net "P0V8_PEX2_EN2")
		)
	)
	(footprint ""
		(layer "B.Cu")
		(at 277.5204 -386.334 180)
		(property "Reference" "PC6603"
			(at 0 0 0)
			(layer "B.SilkS")
			(hide yes)
			(effects
				(font
					(size 1.27 1.27)
				)
				(justify mirror)
			)
		)
		(property "Value" ""
			(at 0 0 0)
			(layer "B.Fab")
			(effects
				(font
					(size 1.27 1.27)
				)
				(justify mirror)
			)
		)
		(duplicate_pad_numbers_are_jumpers no)
		(fp_line
			(start 1.2954 0.5842)
			(end 1.2954 -0.5842)
			(stroke
				(width 0.1524)
				(type default)
			)
			(layer "B.SilkS")
		)
		(fp_line
			(start 1.2954 -0.5842)
			(end -1.2954 -0.5842)
			(stroke
				(width 0.1524)
				(type default)
			)
			(layer "B.SilkS")
		)
		(fp_line
			(start -1.2954 0.5842)
			(end 1.2954 0.5842)
			(stroke
				(width 0.1524)
				(type default)
			)
			(layer "B.SilkS")
		)
		(fp_line
			(start -1.2954 -0.5842)
			(end -1.2954 0.5842)
			(stroke
				(width 0.1524)
				(type default)
			)
			(layer "B.SilkS")
		)
		(fp_line
			(start 1.1938 0.4064)
			(end 1.1938 -0.4064)
			(stroke
				(width 0.1)
				(type default)
			)
			(layer "B.Fab")
		)
		(fp_line
			(start 1.1938 -0.4064)
			(end 0.8636 -0.4064)
			(stroke
				(width 0.1)
				(type default)
			)
			(layer "B.Fab")
		)
		(fp_line
			(start 0.8636 0.4572)
			(end 0.8636 0.4064)
			(stroke
				(width 0.1)
				(type default)
			)
			(layer "B.Fab")
		)
		(fp_line
			(start 0.8636 0.4064)
			(end 1.1938 0.4064)
			(stroke
				(width 0.1)
				(type default)
			)
			(layer "B.Fab")
		)
		(fp_line
			(start 0.8636 -0.4064)
			(end 0.8636 -0.4572)
			(stroke
				(width 0.1)
				(type default)
			)
			(layer "B.Fab")
		)
		(fp_line
			(start 0.8636 -0.4572)
			(end -0.8636 -0.4572)
			(stroke
				(width 0.1)
				(type default)
			)
			(layer "B.Fab")
		)
		(fp_line
			(start -0.8636 0.4572)
			(end 0.8636 0.4572)
			(stroke
				(width 0.1)
				(type default)
			)
			(layer "B.Fab")
		)
		(fp_line
			(start -0.8636 0.4064)
			(end -0.8636 0.4572)
			(stroke
				(width 0.1)
				(type default)
			)
			(layer "B.Fab")
		)
		(fp_line
			(start -0.8636 -0.4064)
			(end -1.1938 -0.4064)
			(stroke
				(width 0.1)
				(type default)
			)
			(layer "B.Fab")
		)
		(fp_line
			(start -0.8636 -0.4572)
			(end -0.8636 -0.4064)
			(stroke
				(width 0.1)
				(type default)
			)
			(layer "B.Fab")
		)
		(fp_line
			(start -1.1938 0.4064)
			(end -0.8636 0.4064)
			(stroke
				(width 0.1)
				(type default)
			)
			(layer "B.Fab")
		)
		(fp_line
			(start -1.1938 -0.4064)
			(end -1.1938 0.4064)
			(stroke
				(width 0.1)
				(type default)
			)
			(layer "B.Fab")
		)
		(pad "1" smd rect
			(at 0.7366 0 90)
			(size 0.7112 0.8128)
			(layers "B.Cu" "B.Mask" "B.Paste")
			(net "LTC4282_TEMP_D+")
		)
		(pad "2" smd rect
			(at -0.7366 0 90)
			(size 0.7112 0.8128)
			(layers "B.Cu" "B.Mask" "B.Paste")
			(net "LTC4282_TEMP_D-")
		)
	)
	(footprint ""
		(layer "B.Cu")
		(at 299.449744 -288.299906 90)
		(property "Reference" "C3284"
			(at 0 0 90)
			(layer "B.SilkS")
			(hide yes)
			(effects
				(font
					(size 1.27 1.27)
				)
				(justify mirror)
			)
		)
		(property "Value" ""
			(at 0 0 90)
			(layer "B.Fab")
			(effects
				(font
					(size 1.27 1.27)
				)
				(justify mirror)
			)
		)
		(duplicate_pad_numbers_are_jumpers no)
		(fp_line
			(start 0.299974 -0.150114)
			(end -0.299974 -0.150114)
			(stroke
				(width 0.1)
				(type default)
			)
			(layer "B.Fab")
		)
		(fp_line
			(start -0.299974 -0.150114)
			(end -0.299974 0.150114)
			(stroke
				(width 0.1)
				(type default)
			)
			(layer "B.Fab")
		)
		(fp_line
			(start 0.299974 0.150114)
			(end 0.299974 -0.150114)
			(stroke
				(width 0.1)
				(type default)
			)
			(layer "B.Fab")
		)
		(fp_line
			(start -0.299974 0.150114)
			(end 0.299974 0.150114)
			(stroke
				(width 0.1)
				(type default)
			)
			(layer "B.Fab")
		)
		(pad "1" smd rect
			(at 0.2667 0 270)
			(size 0.3048 0.381)
			(layers "B.Cu" "B.Mask" "B.Paste")
			(net "P1V25_PEX2")
		)
		(pad "2" smd rect
			(at -0.2667 0 270)
			(size 0.3048 0.381)
			(layers "B.Cu" "B.Mask" "B.Paste")
			(net "GND")
		)
	)
	(footprint ""
		(layer "B.Cu")
		(at 287.099756 -301.599854 -90)
		(property "Reference" "C1712"
			(at 0 0 90)
			(layer "B.SilkS")
			(hide yes)
			(effects
				(font
					(size 1.27 1.27)
				)
				(justify mirror)
			)
		)
		(property "Value" ""
			(at 0 0 90)
			(layer "B.Fab")
			(effects
				(font
					(size 1.27 1.27)
				)
				(justify mirror)
			)
		)
		(duplicate_pad_numbers_are_jumpers no)
		(fp_line
			(start -0.299974 0.150114)
			(end 0.299974 0.150114)
			(stroke
				(width 0.1)
				(type default)
			)
			(layer "B.Fab")
		)
		(fp_line
			(start 0.299974 0.150114)
			(end 0.299974 -0.150114)
			(stroke
				(width 0.1)
				(type default)
			)
			(layer "B.Fab")
		)
		(fp_line
			(start -0.299974 -0.150114)
			(end -0.299974 0.150114)
			(stroke
				(width 0.1)
				(type default)
			)
			(layer "B.Fab")
		)
		(fp_line
			(start 0.299974 -0.150114)
			(end -0.299974 -0.150114)
			(stroke
				(width 0.1)
				(type default)
			)
			(layer "B.Fab")
		)
		(pad "1" smd rect
			(at 0.2667 0 90)
			(size 0.3048 0.381)
			(layers "B.Cu" "B.Mask" "B.Paste")
			(net "P0V8_SERDES_VDDA_PEX2")
		)
		(pad "2" smd rect
			(at -0.2667 0 90)
			(size 0.3048 0.381)
			(layers "B.Cu" "B.Mask" "B.Paste")
			(net "GND")
		)
	)
	(footprint ""
		(layer "B.Cu")
		(at 285.199836 -299.699934 -90)
		(property "Reference" "C1689"
			(at 0 0 90)
			(layer "B.SilkS")
			(hide yes)
			(effects
				(font
					(size 1.27 1.27)
				)
				(justify mirror)
			)
		)
		(property "Value" ""
			(at 0 0 90)
			(layer "B.Fab")
			(effects
				(font
					(size 1.27 1.27)
				)
				(justify mirror)
			)
		)
		(duplicate_pad_numbers_are_jumpers no)
		(fp_line
			(start -0.299974 0.150114)
			(end 0.299974 0.150114)
			(stroke
				(width 0.1)
				(type default)
			)
			(layer "B.Fab")
		)
		(fp_line
			(start 0.299974 0.150114)
			(end 0.299974 -0.150114)
			(stroke
				(width 0.1)
				(type default)
			)
			(layer "B.Fab")
		)
		(fp_line
			(start -0.299974 -0.150114)
			(end -0.299974 0.150114)
			(stroke
				(width 0.1)
				(type default)
			)
			(layer "B.Fab")
		)
		(fp_line
			(start 0.299974 -0.150114)
			(end -0.299974 -0.150114)
			(stroke
				(width 0.1)
				(type default)
			)
			(layer "B.Fab")
		)
		(pad "1" smd rect
			(at 0.2667 0 90)
			(size 0.3048 0.381)
			(layers "B.Cu" "B.Mask" "B.Paste")
			(net "P0V8_SERDES_VDDA_PEX2")
		)
		(pad "2" smd rect
			(at -0.2667 0 90)
			(size 0.3048 0.381)
			(layers "B.Cu" "B.Mask" "B.Paste")
			(net "GND")
		)
	)
	(footprint ""
		(layer "B.Cu")
		(at 332.153514 -209.592418 -90)
		(property "Reference" "R5638"
			(at 0 0 90)
			(layer "B.SilkS")
			(hide yes)
			(effects
				(font
					(size 1.27 1.27)
				)
				(justify mirror)
			)
		)
		(property "Value" ""
			(at 0 0 90)
			(layer "B.Fab")
			(effects
				(font
					(size 1.27 1.27)
				)
				(justify mirror)
			)
		)
		(duplicate_pad_numbers_are_jumpers no)
		(fp_line
			(start -1.2954 0.5842)
			(end 1.2954 0.5842)
			(stroke
				(width 0.1524)
				(type default)
			)
			(layer "B.SilkS")
		)
		(fp_line
			(start 1.2954 0.5842)
			(end 1.2954 -0.5842)
			(stroke
				(width 0.1524)
				(type default)
			)
			(layer "B.SilkS")
		)
		(fp_line
			(start -1.2954 -0.5842)
			(end -1.2954 0.5842)
			(stroke
				(width 0.1524)
				(type default)
			)
			(layer "B.SilkS")
		)
		(fp_line
			(start 1.2954 -0.5842)
			(end -1.2954 -0.5842)
			(stroke
				(width 0.1524)
				(type default)
			)
			(layer "B.SilkS")
		)
		(fp_line
			(start -0.8636 0.4572)
			(end 0.8636 0.4572)
			(stroke
				(width 0.1)
				(type default)
			)
			(layer "B.Fab")
		)
		(fp_line
			(start 0.8636 0.4572)
			(end 0.8636 0.4318)
			(stroke
				(width 0.1)
				(type default)
			)
			(layer "B.Fab")
		)
		(fp_line
			(start 0.8636 0.4318)
			(end 0.8636 0.4064)
			(stroke
				(width 0.1)
				(type default)
			)
			(layer "B.Fab")
		)
		(fp_line
			(start -1.1938 0.4064)
			(end -0.8636 0.4064)
			(stroke
				(width 0.1)
				(type default)
			)
			(layer "B.Fab")
		)
		(fp_line
			(start -0.8636 0.4064)
			(end -0.8636 0.4572)
			(stroke
				(width 0.1)
				(type default)
			)
			(layer "B.Fab")
		)
		(fp_line
			(start 0.8636 0.4064)
			(end 1.1938 0.4064)
			(stroke
				(width 0.1)
				(type default)
			)
			(layer "B.Fab")
		)
		(fp_line
			(start 1.1938 0.4064)
			(end 1.1938 -0.406654)
			(stroke
				(width 0.1)
				(type default)
			)
			(layer "B.Fab")
		)
		(fp_line
			(start -1.1938 -0.406654)
			(end -1.1938 0.4064)
			(stroke
				(width 0.1)
				(type default)
			)
			(layer "B.Fab")
		)
		(fp_line
			(start -0.8636 -0.406654)
			(end -1.1938 -0.406654)
			(stroke
				(width 0.1)
				(type default)
			)
			(layer "B.Fab")
		)
		(fp_line
			(start 0.8636 -0.406654)
			(end 0.8636 -0.4572)
			(stroke
				(width 0.1)
				(type default)
			)
			(layer "B.Fab")
		)
		(fp_line
			(start 1.1938 -0.406654)
			(end 0.8636 -0.406654)
			(stroke
				(width 0.1)
				(type default)
			)
			(layer "B.Fab")
		)
		(fp_line
			(start -0.8636 -0.4572)
			(end -0.8636 -0.406654)
			(stroke
				(width 0.1)
				(type default)
			)
			(layer "B.Fab")
		)
		(fp_line
			(start 0.8636 -0.4572)
			(end -0.8636 -0.4572)
			(stroke
				(width 0.1)
				(type default)
			)
			(layer "B.Fab")
		)
		(pad "1" smd rect
			(at 0.7366 0 180)
			(size 0.7112 0.8128)
			(layers "B.Cu" "B.Mask" "B.Paste")
			(net "P3V3_AUX")
		)
		(pad "2" smd rect
			(at -0.7366 0 180)
			(size 0.7112 0.8128)
			(layers "B.Cu" "B.Mask" "B.Paste")
			(net "P3V3_FPGA_VCCIO2")
		)
	)
	(footprint ""
		(layer "B.Cu")
		(at 51.099974 -301.599854 -90)
		(property "Reference" "C1178"
			(at 0 0 90)
			(layer "B.SilkS")
			(hide yes)
			(effects
				(font
					(size 1.27 1.27)
				)
				(justify mirror)
			)
		)
		(property "Value" ""
			(at 0 0 90)
			(layer "B.Fab")
			(effects
				(font
					(size 1.27 1.27)
				)
				(justify mirror)
			)
		)
		(duplicate_pad_numbers_are_jumpers no)
		(fp_line
			(start -0.299974 0.150114)
			(end 0.299974 0.150114)
			(stroke
				(width 0.1)
				(type default)
			)
			(layer "B.Fab")
		)
		(fp_line
			(start 0.299974 0.150114)
			(end 0.299974 -0.150114)
			(stroke
				(width 0.1)
				(type default)
			)
			(layer "B.Fab")
		)
		(fp_line
			(start -0.299974 -0.150114)
			(end -0.299974 0.150114)
			(stroke
				(width 0.1)
				(type default)
			)
			(layer "B.Fab")
		)
		(fp_line
			(start 0.299974 -0.150114)
			(end -0.299974 -0.150114)
			(stroke
				(width 0.1)
				(type default)
			)
			(layer "B.Fab")
		)
		(pad "1" smd rect
			(at 0.2667 0 90)
			(size 0.3048 0.381)
			(layers "B.Cu" "B.Mask" "B.Paste")
			(net "P0V8_SERDES_VDDA_PEX0")
		)
		(pad "2" smd rect
			(at -0.2667 0 90)
			(size 0.3048 0.381)
			(layers "B.Cu" "B.Mask" "B.Paste")
			(net "GND")
		)
	)
	(footprint ""
		(layer "B.Cu")
		(at 301.536354 -236.736636 -90)
		(property "Reference" "R1869"
			(at 0 0 90)
			(layer "B.SilkS")
			(hide yes)
			(effects
				(font
					(size 1.27 1.27)
				)
				(justify mirror)
			)
		)
		(property "Value" ""
			(at 0 0 90)
			(layer "B.Fab")
			(effects
				(font
					(size 1.27 1.27)
				)
				(justify mirror)
			)
		)
		(duplicate_pad_numbers_are_jumpers no)
		(fp_line
			(start -0.7874 0.4064)
			(end 0.7874 0.4064)
			(stroke
				(width 0.1524)
				(type default)
			)
			(layer "B.SilkS")
		)
		(fp_line
			(start 0.7874 0.4064)
			(end 0.7874 -0.4064)
			(stroke
				(width 0.1524)
				(type default)
			)
			(layer "B.SilkS")
		)
		(fp_line
			(start -0.7874 -0.4064)
			(end -0.7874 0.4064)
			(stroke
				(width 0.1524)
				(type default)
			)
			(layer "B.SilkS")
		)
		(fp_line
			(start 0.7874 -0.4064)
			(end -0.7874 -0.4064)
			(stroke
				(width 0.1524)
				(type default)
			)
			(layer "B.SilkS")
		)
		(fp_line
			(start -0.67945 0.3048)
			(end -0.120396 0.3048)
			(stroke
				(width 0.1)
				(type default)
			)
			(layer "B.Fab")
		)
		(fp_line
			(start -0.120396 0.3048)
			(end -0.120396 0.2794)
			(stroke
				(width 0.1)
				(type default)
			)
			(layer "B.Fab")
		)
		(fp_line
			(start 0.12065 0.3048)
			(end 0.67945 0.3048)
			(stroke
				(width 0.1)
				(type default)
			)
			(layer "B.Fab")
		)
		(fp_line
			(start 0.67945 0.3048)
			(end 0.67945 -0.305054)
			(stroke
				(width 0.1)
				(type default)
			)
			(layer "B.Fab")
		)
		(fp_line
			(start -0.120396 0.2794)
			(end 0.12065 0.2794)
			(stroke
				(width 0.1)
				(type default)
			)
			(layer "B.Fab")
		)
		(fp_line
			(start 0.12065 0.2794)
			(end 0.12065 0.3048)
			(stroke
				(width 0.1)
				(type default)
			)
			(layer "B.Fab")
		)
		(fp_line
			(start -0.12065 -0.2794)
			(end -0.12065 -0.3048)
			(stroke
				(width 0.1)
				(type default)
			)
			(layer "B.Fab")
		)
		(fp_line
			(start 0.12065 -0.2794)
			(end -0.12065 -0.2794)
			(stroke
				(width 0.1)
				(type default)
			)
			(layer "B.Fab")
		)
		(fp_line
			(start -0.67945 -0.3048)
			(end -0.67945 0.3048)
			(stroke
				(width 0.1)
				(type default)
			)
			(layer "B.Fab")
		)
		(fp_line
			(start -0.12065 -0.3048)
			(end -0.67945 -0.3048)
			(stroke
				(width 0.1)
				(type default)
			)
			(layer "B.Fab")
		)
		(fp_line
			(start 0.12065 -0.305054)
			(end 0.12065 -0.2794)
			(stroke
				(width 0.1)
				(type default)
			)
			(layer "B.Fab")
		)
		(fp_line
			(start 0.67945 -0.305054)
			(end 0.12065 -0.305054)
			(stroke
				(width 0.1)
				(type default)
			)
			(layer "B.Fab")
		)
		(pad "1" smd circle
			(at 0.40005 0 90)
			(size 0 0)
			(layers "B.Cu" "B.Mask" "B.Paste")
			(net "RST_GPU_PERST_2_BUF_N")
		)
		(pad "2" smd circle
			(at -0.40005 0 90)
			(size 0 0)
			(layers "B.Cu" "B.Mask" "B.Paste")
			(net "RST_GPU_PERST_2_BUF_R_N")
		)
	)
)
